;LEADER: 12
;HEADER:
;CODE  : ASCII
;FILE  : DAT6MTH3AD0_t6m_cm_d_brd_103112_274-1-10.drl for board DAT6MTH3AD0_t6m_cm_d_brd_103112_274.brd ... layers TOP and BOTTOM
;   Holesize 1. = 10.000000 Tolerance = +3.000000/-3.000000 PLATED MILS Quantity = 6028
;   Holesize 2. = 10.000000 Tolerance = +4.000000/-10.000000 PLATED MILS Quantity = 12
;   Holesize 3. = 22.000000 Tolerance = +3.000000/-3.000000 PLATED MILS Quantity = 8
;   Holesize 4. = 26.000000 Tolerance = +3.000000/-3.000000 PLATED MILS Quantity = 7
;   Holesize 5. = 33.000000 Tolerance = +3.000000/-3.000000 PLATED MILS Quantity = 15
;   Holesize 6. = 36.000000 Tolerance = +3.000000/-3.000000 PLATED MILS Quantity = 8
;   Holesize 7. = 40.000000 Tolerance = +3.000000/-3.000000 PLATED MILS Quantity = 25
;   Holesize 8. = 41.000000 Tolerance = +3.000000/-3.000000 PLATED MILS Quantity = 2
;   Holesize 9. = 44.000000 Tolerance = +3.000000/-3.000000 PLATED MILS Quantity = 1
;   Holesize 10. = 46.000000 Tolerance = +3.000000/-3.000000 PLATED MILS Quantity = 30
;   Holesize 11. = 48.000000 Tolerance = +3.000000/-3.000000 PLATED MILS Quantity = 4
;   Holesize 12. = 56.000000 Tolerance = +3.000000/-3.000000 PLATED MILS Quantity = 2
;   Holesize 13. = 57.000000 Tolerance = +3.000000/-3.000000 PLATED MILS Quantity = 4
;   Holesize 14. = 90.000000 Tolerance = +3.000000/-3.000000 PLATED MILS Quantity = 8
;   Holesize 15. = 213.000000 Tolerance = +2.000000/-2.000000 PLATED MILS Quantity = 1
;   Holesize 16. = 42.000000 Tolerance = +2.000000/-2.000000 NON_PLATED MILS Quantity = 2
;   Holesize 17. = 46.000000 Tolerance = +2.000000/-2.000000 NON_PLATED MILS Quantity = 1
;   Holesize 18. = 47.000000 Tolerance = +2.000000/-2.000000 NON_PLATED MILS Quantity = 4
;   Holesize 19. = 50.000000 Tolerance = +2.000000/-2.000000 NON_PLATED MILS Quantity = 16
;   Holesize 20. = 59.000000 Tolerance = +2.000000/-2.000000 NON_PLATED MILS Quantity = 2
;   Holesize 21. = 65.000000 Tolerance = +2.000000/-2.000000 NON_PLATED MILS Quantity = 1
;   Holesize 22. = 118.000000 Tolerance = +2.000000/-2.000000 NON_PLATED MILS Quantity = 4
;   Holesize 23. = 120.000000 Tolerance = +2.000000/-2.000000 NON_PLATED MILS Quantity = 2
;   Holesize 24. = 142.000000 Tolerance = +2.000000/-2.000000 NON_PLATED MILS Quantity = 2
;   Holesize 25. = 150.000000 Tolerance = +2.000000/-2.000000 NON_PLATED MILS Quantity = 2
;   Holesize 26. = 158.000000 Tolerance = +2.000000/-2.000000 NON_PLATED MILS Quantity = 1
